(kicad_pcb
	(version 20221018)
	(generator pcbnew)
	(general
    (thickness 1.6)
  )
	(paper "A4")
	(title_block
    (title "NUC Computer Cluster Power Breakout HW")
    (date "2023-10-18")
    (rev "1.4.3")
    (company "Antmicro Ltd.")
		(comment 9 "footprints 207-212 of 234")
	)
	(layers
    (0 "F.Cu" mixed)
    (1 "In1.Cu" power)
    (2 "In2.Cu" mixed)
    (31 "B.Cu" power)
    (32 "B.Adhes" user "B.Adhesive")
    (33 "F.Adhes" user "F.Adhesive")
    (34 "B.Paste" user)
    (35 "F.Paste" user)
    (36 "B.SilkS" user "B.Silkscreen")
    (37 "F.SilkS" user "F.Silkscreen")
    (38 "B.Mask" user)
    (39 "F.Mask" user)
    (40 "Dwgs.User" user "User.Drawings")
    (41 "Cmts.User" user "User.Comments")
    (42 "Eco1.User" user "User.Eco1")
    (43 "Eco2.User" user "User.Eco2")
    (44 "Edge.Cuts" user)
    (45 "Margin" user)
    (46 "B.CrtYd" user "B.Courtyard")
    (47 "F.CrtYd" user "F.Courtyard")
    (48 "B.Fab" user)
    (49 "F.Fab" user)
  )
	(footprint "antmicro-footprints:LED_0603_1608Metric_G" (layer "F.Cu")
    (at 94.2 99)
    (descr "LED SMD 0603 Green")
    (tags "LED SMD 0603 Green")
    (property "Author" "Antmicro")
    (property "Color" "Green")
    (property "License" "Apache-2.0")
    (property "MPN" "LG L29K-G2J1-24-Z")
    (property "Manufacturer" "OSRAM")
    (property "Sheetfile" "d1600e-psu-breakout-board.kicad_sch")
    (property "Sheetname" "")
    (property "ki_description" "LED, Green, SMD, 0603, 20 mA, 1.7 V, 570 nm")
    (property "ki_keywords" "SMT, DIODE, SEMICONDUCTOR, LED")
    (zone_connect 1)
    (attr smd)
    (fp_text reference "D10" (at -1.2 -0.7) (layer "F.SilkS")
        (effects (font (size 0.7 0.7) (thickness 0.15)) (justify left bottom))
    )
    (fp_text value "LED_G_0603_LG_L29K-G2J1-24-Z" (at -0.001 1.599) (layer "F.Fab")
        (effects (font (size 0.7 0.7) (thickness 0.15)) (justify left bottom))
    )
    (fp_text user "License: Apache-2.0" (at -1.4224 3.599) (layer "F.Fab") hide
        (effects (font (size 0.7 0.7) (thickness 0.15)) (justify left bottom))
    )
    (fp_text user "${REFERENCE}" (at -1.4224 5.999) (layer "F.Fab") hide
        (effects (font (size 0.7 0.7) (thickness 0.15)) (justify left bottom))
    )
    (fp_text user "Author: Antmicro" (at -1.4224 4.799) (layer "F.Fab") hide
        (effects (font (size 0.7 0.7) (thickness 0.15)) (justify left bottom))
    )
    (fp_line (start -1.18 -0.319) (end -1.18 0.321)
      (stroke (width 0.15) (type solid)) (layer "F.SilkS"))
    (fp_line (start -0.094672 0.001008) (end -0.24 0.001008)
      (stroke (width 0.1) (type solid)) (layer "F.SilkS"))
    (fp_line (start -0.094672 0.001008) (end 0.105328 -0.198992)
      (stroke (width 0.1) (type solid)) (layer "F.SilkS"))
    (fp_line (start -0.094672 0.201008) (end -0.094672 -0.198992)
      (stroke (width 0.1) (type solid)) (layer "F.SilkS"))
    (fp_line (start 0.105328 0.001008) (end 0.24 0.001)
      (stroke (width 0.1) (type solid)) (layer "F.SilkS"))
    (fp_line (start 0.105328 0.201008) (end -0.094672 0.001008)
      (stroke (width 0.1) (type solid)) (layer "F.SilkS"))
    (fp_line (start 0.105328 0.201008) (end 0.105328 -0.198992)
      (stroke (width 0.1) (type solid)) (layer "F.SilkS"))
    (fp_line (start 0.22 -0.35) (end -0.22 -0.35)
      (stroke (width 0.15) (type solid)) (layer "F.SilkS"))
    (fp_line (start 0.22 0.35) (end -0.22 0.35)
      (stroke (width 0.15) (type solid)) (layer "F.SilkS"))
    (fp_rect (start 1.25 0.65) (end -1.25 -0.65)
      (stroke (width 0.05) (type solid)) (fill none) (layer "F.CrtYd"))
    (fp_line (start -0.199 -0.202) (end -0.199 0.1)
      (stroke (width 0.15) (type solid)) (layer "F.Fab"))
    (fp_line (start -0.199 0) (end -0.597 0)
      (stroke (width 0.15) (type solid)) (layer "F.Fab"))
    (fp_line (start -0.199 0.2) (end -0.199 0.1)
      (stroke (width 0.15) (type solid)) (layer "F.Fab"))
    (fp_line (start -0.101 0) (end 0.201 0.2)
      (stroke (width 0.15) (type solid)) (layer "F.Fab"))
    (fp_line (start 0.201 -0.202) (end -0.101 0)
      (stroke (width 0.15) (type solid)) (layer "F.Fab"))
    (fp_line (start 0.201 0) (end 0.201 -0.202)
      (stroke (width 0.15) (type solid)) (layer "F.Fab"))
    (fp_line (start 0.201 0.2) (end 0.201 0)
      (stroke (width 0.15) (type solid)) (layer "F.Fab"))
    (fp_line (start 0.599 0) (end 0.201 0)
      (stroke (width 0.15) (type solid)) (layer "F.Fab"))
    (fp_rect (start 0.848 0.4) (end -0.85 -0.402)
      (stroke (width 0.15) (type solid)) (fill none) (layer "F.Fab"))
    (pad "1" smd roundrect (at -0.7 0 180) (size 0.8 1) (layers "F.Cu" "F.Paste" "F.Mask") (roundrect_rratio 0.2)
      (net 4 "GND") (pinfunction "C") (pintype "passive"))
    (pad "2" smd roundrect (at 0.7 0 180) (size 0.8 1) (layers "F.Cu" "F.Paste" "F.Mask") (roundrect_rratio 0.2)
      (net 79 "Net-(D10-A)") (pinfunction "A") (pintype "passive"))
  )
	(footprint "antmicro-footprints:R_0402_1005Metric" (layer "F.Cu")
    (at 162.3 89.5 180)
    (descr "Resistor SMD 0402")
    (tags "resistor SMD 0402")
    (property "Author" "Antmicro")
    (property "DNP" "DNP")
    (property "License" "Apache-2.0")
    (property "MPN" "CR0402-FX-1002GLF")
    (property "Manufacturer" "Bourns")
    (property "Sheetfile" "power-switch.kicad_sch")
    (property "Sheetname" "Power switch 4")
    (property "Tolerance" "1%")
    (property "Val" "10k")
    (property "dnp" "")
    (property "exclude_from_bom" "")
    (property "ki_description" "SMD Chip Resistor, 10 kohm, ± 1%, 62.5 mW, 0402 [1005 Metric], Thick Film, General Purpose")
    (property "ki_keywords" "0402, SMT, RESISTOR, PASSIVE")
    (attr smd exclude_from_bom)
    (fp_text reference "R49" (at 2.1 0) (layer "F.SilkS")
        (effects (font (size 0.7 0.7) (thickness 0.15)))
    )
    (fp_text value "R_10k_0402" (at 0 1.17) (layer "F.Fab") hide
        (effects (font (size 1 1) (thickness 0.15)))
    )
    (fp_text user "Author: Antmicro" (at -0.95 4.169 180) (layer "F.Fab") hide
        (effects (font (size 0.7 0.7) (thickness 0.15)) (justify left bottom))
    )
    (fp_text user "${REFERENCE}" (at 0 0) (layer "F.Fab")
        (effects (font (size 0.25 0.25) (thickness 0.04)))
    )
    (fp_text user "License: Apache-2.0" (at -0.95 5.169 180) (layer "F.Fab") hide
        (effects (font (size 0.7 0.7) (thickness 0.15)) (justify left bottom))
    )
    (fp_rect (start -0.925 -0.47) (end 0.925 0.47)
      (stroke (width 0.05) (type default)) (fill none) (layer "F.CrtYd"))
    (fp_rect (start -0.5 -0.25) (end 0.5 0.25)
      (stroke (width 0.15) (type solid)) (fill none) (layer "F.Fab"))
    (pad "1" smd roundrect (at -0.48 0 180) (size 0.59 0.64) (layers "F.Cu" "F.Paste" "F.Mask") (roundrect_rratio 0.25)
      (net 29 "/Power Cycling & Current Measurement/PC_4") (pintype "passive"))
    (pad "2" smd roundrect (at 0.48 0 180) (size 0.59 0.64) (layers "F.Cu" "F.Paste" "F.Mask") (roundrect_rratio 0.25)
      (net 4 "GND") (pintype "passive"))
  )
	(footprint "antmicro-footprints:R_0603_1608Metric" (layer "F.Cu")
    (at 96.9 101.6)
    (descr "Resistor SMD 0603")
    (tags "resistor SMD 0603")
    (property "Author" "Antmicro")
    (property "License" "Apache-2.0")
    (property "MPN" "CR0603-FX-1001ELF")
    (property "Manufacturer" "Bourns")
    (property "Sheetfile" "d1600e-psu-breakout-board.kicad_sch")
    (property "Sheetname" "")
    (property "Tolerance" "1%")
    (property "Val" "1k")
    (property "ki_description" "SMD Chip Resistor, 1 kohm, ± 1%, 100 mW, 0603 [1608 Metric], Thick Film, General Purpose")
    (property "ki_keywords" "0603, SMT, RESISTOR, PASSIVE")
    (attr smd)
    (fp_text reference "R54" (at -1.15 -0.65) (layer "F.SilkS")
        (effects (font (size 0.7 0.7) (thickness 0.15)) (justify left bottom))
    )
    (fp_text value "R_1k_0603" (at 0 1.6) (layer "F.Fab")
        (effects (font (size 0.7 0.7) (thickness 0.15)) (justify left bottom))
    )
    (fp_text user "License: Apache-2.0" (at -1.25 5.9) (layer "F.Fab") hide
        (effects (font (size 0.7 0.7) (thickness 0.15)) (justify left bottom))
    )
    (fp_text user "Author: Antmicro" (at -1.25 4.9) (layer "F.Fab") hide
        (effects (font (size 0.7 0.7) (thickness 0.15)) (justify left bottom))
    )
    (fp_text user "${REFERENCE}" (at -1.25 3.898) (layer "F.Fab") hide
        (effects (font (size 0.7 0.7) (thickness 0.15)) (justify left bottom))
    )
    (fp_line (start -0.15 -0.4) (end 0.15 -0.4)
      (stroke (width 0.15) (type solid)) (layer "F.SilkS"))
    (fp_line (start -0.15 0.4) (end 0.15 0.4)
      (stroke (width 0.15) (type solid)) (layer "F.SilkS"))
    (fp_rect (start -1.25 -0.65) (end 1.25 0.65)
      (stroke (width 0.05) (type solid)) (fill none) (layer "F.CrtYd"))
    (fp_rect (start -0.8 -0.4) (end 0.8 0.4)
      (stroke (width 0.15) (type solid)) (fill none) (layer "F.Fab"))
    (pad "1" smd roundrect (at -0.7 0) (size 0.8 1) (layers "F.Cu" "F.Paste" "F.Mask") (roundrect_rratio 0.2)
      (net 78 "Net-(D9-A)") (pintype "passive"))
    (pad "2" smd roundrect (at 0.7 0) (size 0.8 1) (layers "F.Cu" "F.Paste" "F.Mask") (roundrect_rratio 0.2)
      (net 1 "VCC3V3") (pintype "passive"))
  )
	(footprint "antmicro-footprints:R_0402_1005Metric" (layer "F.Cu")
    (at 180 90.7 90)
    (descr "Resistor SMD 0402")
    (tags "resistor SMD 0402")
    (property "Author" "Antmicro")
    (property "License" "Apache-2.0")
    (property "MPN" "CR0402-FX-2R00GLF")
    (property "Manufacturer" "Bourns")
    (property "Sheetfile" "power-switch.kicad_sch")
    (property "Sheetname" "Power switch 5")
    (property "Tolerance" "1%")
    (property "Val" "2R")
    (property "ki_description" "SMD Chip Resistor")
    (property "ki_keywords" "0402, SMT, RESISTOR, PASSIVE")
    (attr smd)
    (fp_text reference "R69" (at -2 -0.772697 90) (layer "F.SilkS")
        (effects (font (size 0.7 0.7) (thickness 0.15)) (justify left bottom))
    )
    (fp_text value "R_2R_0402" (at -1.011843 1.772047 90) (layer "F.Fab")
        (effects (font (size 0.7 0.7) (thickness 0.15)) (justify left bottom))
    )
    (fp_text user "Author: Antmicro" (at -0.95 4.169 90) (layer "F.Fab") hide
        (effects (font (size 0.7 0.7) (thickness 0.15)) (justify left bottom))
    )
    (fp_text user "License: Apache-2.0" (at -0.95 5.169 90) (layer "F.Fab") hide
        (effects (font (size 0.7 0.7) (thickness 0.15)) (justify left bottom))
    )
    (fp_text user "${REFERENCE}" (at -0.95 3.168 90) (layer "F.Fab") hide
        (effects (font (size 0.7 0.7) (thickness 0.15)) (justify left bottom))
    )
    (fp_rect (start -0.925 -0.47) (end 0.925 0.47)
      (stroke (width 0.05) (type default)) (fill none) (layer "F.CrtYd"))
    (fp_rect (start -0.5 -0.25) (end 0.5 0.25)
      (stroke (width 0.15) (type solid)) (fill none) (layer "F.Fab"))
    (pad "1" smd roundrect (at -0.48 0 90) (size 0.59 0.64) (layers "F.Cu" "F.Paste" "F.Mask") (roundrect_rratio 0.25)
      (net 87 "Net-(D19-A)") (pintype "passive"))
    (pad "2" smd roundrect (at 0.48 0 90) (size 0.59 0.64) (layers "F.Cu" "F.Paste" "F.Mask") (roundrect_rratio 0.25)
      (net 97 "Net-(QA5-G)") (pintype "passive"))
  )
	(footprint "antmicro-footprints:Vishay_PowerPAK_1212-8_Single" (layer "F.Cu")
    (at 116.5 86.95 90)
    (descr "PowerPAK 1212-8 Single")
    (tags "Vishay PowerPAK 1212-8 Single")
    (property "Author" "Antmicro")
    (property "License" "Apache-2.0")
    (property "MPN" "SI7613DN-T1-GE3")
    (property "Manufacturer" "Vishay")
    (property "Sheetfile" "power-switch.kicad_sch")
    (property "Sheetname" "Power switch 1")
    (property "ki_description" "Power MOSFET, P Channel, 20 V, 35 A, 0.0072 ohm, PowerPAK 1212, Surface Mount")
    (property "ki_keywords" "SMT, TRANSISTOR, SEMICONDUCTOR, MOSFET, PMOS")
    (attr smd)
    (fp_text reference "QB1" (at -2.9 -1.05 180) (layer "F.SilkS")
        (effects (font (size 0.7 0.7) (thickness 0.15)) (justify left bottom))
    )
    (fp_text value "SI7613DN-T1-GE3" (at 0 2.7 90) (layer "F.Fab")
        (effects (font (size 0.7 0.7) (thickness 0.15)) (justify left bottom))
    )
    (fp_text user "${REFERENCE}" (at -8 4.7 90) (layer "F.Fab") hide
        (effects (font (size 0.7 0.7) (thickness 0.15)) (justify left bottom))
    )
    (fp_text user "License: Apache-2.0" (at -8 7.1 90) (layer "F.Fab") hide
        (effects (font (size 0.7 0.7) (thickness 0.15)) (justify left bottom))
    )
    (fp_text user "Author: Antmicro" (at -8 5.9 90) (layer "F.Fab") hide
        (effects (font (size 0.7 0.7) (thickness 0.15)) (justify left bottom))
    )
    (fp_line (start -1.651 -1.651) (end -1.651 -1.317)
      (stroke (width 0.15) (type solid)) (layer "F.SilkS"))
    (fp_line (start -1.651 -1.651) (end 1.648 -1.651)
      (stroke (width 0.15) (type solid)) (layer "F.SilkS"))
    (fp_line (start -1.635 1.3) (end -1.635 1.634)
      (stroke (width 0.15) (type solid)) (layer "F.SilkS"))
    (fp_line (start -1.635 1.634) (end 1.634 1.634)
      (stroke (width 0.15) (type solid)) (layer "F.SilkS"))
    (fp_line (start 1.634 1.3) (end 1.634 1.634)
      (stroke (width 0.15) (type solid)) (layer "F.SilkS"))
    (fp_line (start 1.648 -1.651) (end 1.648 -1.317)
      (stroke (width 0.15) (type solid)) (layer "F.SilkS"))
    (fp_circle (center -1.9 -1.4) (end -1.85 -1.4)
      (stroke (width 0.15) (type solid)) (fill solid) (layer "F.SilkS"))
    (fp_rect (start -2 -1.8) (end 2 1.798)
      (stroke (width 0.05) (type solid)) (fill none) (layer "F.CrtYd"))
    (fp_line (start -1.6425 -1.4175) (end -1.4175 -1.6425)
      (stroke (width 0.15) (type solid)) (layer "F.Fab"))
    (fp_rect (start -1.651 -1.651) (end 1.648 1.648)
      (stroke (width 0.15) (type solid)) (fill none) (layer "F.Fab"))
    (pad "1" smd rect (at -1.436 -0.99 90) (size 0.99 0.405) (layers "F.Cu" "F.Paste" "F.Mask")
      (net 11 "VCC12V0") (pinfunction "S") (pintype "passive"))
    (pad "2" smd rect (at -1.436 -0.332 90) (size 0.99 0.405) (layers "F.Cu" "F.Paste" "F.Mask")
      (net 11 "VCC12V0") (pinfunction "S") (pintype "passive"))
    (pad "3" smd rect (at -1.436 0.33 90) (size 0.99 0.405) (layers "F.Cu" "F.Paste" "F.Mask")
      (net 11 "VCC12V0") (pinfunction "S") (pintype "passive"))
    (pad "4" smd rect (at -1.436 0.988 90) (size 0.99 0.405) (layers "F.Cu" "F.Paste" "F.Mask")
      (net 98 "Net-(QB1-G)") (pinfunction "G") (pintype "passive"))
    (pad "5" smd custom (at 0.557 0 90) (size 1.725 2.235) (layers "F.Cu" "F.Paste" "F.Mask")
      (net 21 "C_MEAS_1") (pinfunction "D") (pintype "passive") (zone_connect 2)
      (options (clearance outline) (anchor rect))
      (primitives
        (gr_poly
          (pts
            (xy 0.8625 0.1275)
            (xy 0.8625 -0.1275)
            (xy 1.3725 -0.1275)
            (xy 1.3725 -0.5325)
            (xy 0.8625 -0.5325)
            (xy 0.8625 -0.7875)
            (xy 1.3725 -0.7875)
            (xy 1.3725 -1.195)
            (xy 0.6125 -1.195)
            (xy 0.6125 1.195)
            (xy 1.3725 1.195)
            (xy 1.3725 0.7875)
            (xy 0.8625 0.7875)
            (xy 0.8625 0.5325)
            (xy 1.3725 0.5325)
            (xy 1.3725 0.1275)
          )
          (width 0) (fill yes))
      ))
  )
	(footprint "antmicro-footprints:Vishay_PowerPAK_1212-8_Single" (layer "F.Cu")
    (at 150.2275 87.2 90)
    (descr "PowerPAK 1212-8 Single")
    (tags "Vishay PowerPAK 1212-8 Single")
    (property "Author" "Antmicro")
    (property "License" "Apache-2.0")
    (property "MPN" "SI7613DN-T1-GE3")
    (property "Manufacturer" "Vishay")
    (property "Sheetfile" "power-switch.kicad_sch")
    (property "Sheetname" "Power switch 3")
    (property "ki_description" "Power MOSFET, P Channel, 20 V, 35 A, 0.0072 ohm, PowerPAK 1212, Surface Mount")
    (property "ki_keywords" "SMT, TRANSISTOR, SEMICONDUCTOR, MOSFET, PMOS")
    (attr smd)
    (fp_text reference "QA3" (at -2.95 -1.0275 180) (layer "F.SilkS")
        (effects (font (size 0.7 0.7) (thickness 0.15)) (justify left bottom))
    )
    (fp_text value "SI7613DN-T1-GE3" (at 0 2.7 90) (layer "F.Fab")
        (effects (font (size 0.7 0.7) (thickness 0.15)) (justify left bottom))
    )
    (fp_text user "License: Apache-2.0" (at -8 7.1 90) (layer "F.Fab") hide
        (effects (font (size 0.7 0.7) (thickness 0.15)) (justify left bottom))
    )
    (fp_text user "${REFERENCE}" (at -8 4.7 90) (layer "F.Fab") hide
        (effects (font (size 0.7 0.7) (thickness 0.15)) (justify left bottom))
    )
    (fp_text user "Author: Antmicro" (at -8 5.9 90) (layer "F.Fab") hide
        (effects (font (size 0.7 0.7) (thickness 0.15)) (justify left bottom))
    )
    (fp_line (start -1.651 -1.651) (end -1.651 -1.317)
      (stroke (width 0.15) (type solid)) (layer "F.SilkS"))
    (fp_line (start -1.651 -1.651) (end 1.648 -1.651)
      (stroke (width 0.15) (type solid)) (layer "F.SilkS"))
    (fp_line (start -1.635 1.3) (end -1.635 1.634)
      (stroke (width 0.15) (type solid)) (layer "F.SilkS"))
    (fp_line (start -1.635 1.634) (end 1.634 1.634)
      (stroke (width 0.15) (type solid)) (layer "F.SilkS"))
    (fp_line (start 1.634 1.3) (end 1.634 1.634)
      (stroke (width 0.15) (type solid)) (layer "F.SilkS"))
    (fp_line (start 1.648 -1.651) (end 1.648 -1.317)
      (stroke (width 0.15) (type solid)) (layer "F.SilkS"))
    (fp_circle (center -1.9 -1.4) (end -1.85 -1.4)
      (stroke (width 0.15) (type solid)) (fill solid) (layer "F.SilkS"))
    (fp_rect (start -2 -1.8) (end 2 1.798)
      (stroke (width 0.05) (type solid)) (fill none) (layer "F.CrtYd"))
    (fp_line (start -1.6425 -1.4175) (end -1.4175 -1.6425)
      (stroke (width 0.15) (type solid)) (layer "F.Fab"))
    (fp_rect (start -1.651 -1.651) (end 1.648 1.648)
      (stroke (width 0.15) (type solid)) (fill none) (layer "F.Fab"))
    (pad "1" smd rect (at -1.436 -0.99 90) (size 0.99 0.405) (layers "F.Cu" "F.Paste" "F.Mask")
      (net 11 "VCC12V0") (pinfunction "S") (pintype "passive"))
    (pad "2" smd rect (at -1.436 -0.332 90) (size 0.99 0.405) (layers "F.Cu" "F.Paste" "F.Mask")
      (net 11 "VCC12V0") (pinfunction "S") (pintype "passive"))
    (pad "3" smd rect (at -1.436 0.33 90) (size 0.99 0.405) (layers "F.Cu" "F.Paste" "F.Mask")
      (net 11 "VCC12V0") (pinfunction "S") (pintype "passive"))
    (pad "4" smd rect (at -1.436 0.988 90) (size 0.99 0.405) (layers "F.Cu" "F.Paste" "F.Mask")
      (net 95 "Net-(QA3-G)") (pinfunction "G") (pintype "passive"))
    (pad "5" smd custom (at 0.557 0 90) (size 1.725 2.235) (layers "F.Cu" "F.Paste" "F.Mask")
      (net 28 "C_MEAS_3") (pinfunction "D") (pintype "passive") (zone_connect 2)
      (options (clearance outline) (anchor rect))
      (primitives
        (gr_poly
          (pts
            (xy 0.8625 0.1275)
            (xy 0.8625 -0.1275)
            (xy 1.3725 -0.1275)
            (xy 1.3725 -0.5325)
            (xy 0.8625 -0.5325)
            (xy 0.8625 -0.7875)
            (xy 1.3725 -0.7875)
            (xy 1.3725 -1.195)
            (xy 0.6125 -1.195)
            (xy 0.6125 1.195)
            (xy 1.3725 1.195)
            (xy 1.3725 0.7875)
            (xy 0.8625 0.7875)
            (xy 0.8625 0.5325)
            (xy 1.3725 0.5325)
            (xy 1.3725 0.1275)
          )
          (width 0) (fill yes))
      ))
  )
)
